# BASEBOARD_FAB2 (Tioga Pass) — schematic netlist excerpt (pin names and nets, part order shuffled) for the footprints in the layout excerpt that follows; sources: Cadence DE-HDL packaged netlist, KiCad conversion of Wiwynn_Tioga_Pass_MB.brd

DS9A6  LED  IC  pkg A1LF  page 177 : A = LED_P5V_STBY ; C = GND
R8G22  RES  0.0 5% CHIP  pkg 0402  page 189 : A = JTAG_TCK ; B = JTAG_TCK_R

(kicad_pcb
	(version 20260206)
	(generator "pcbnew")
	(generator_version "10.0")
	(general
		(thickness 1.6)
		(legacy_teardrops no)
	)
	(paper "A4")
	(title_block
		(title "Wiwynn_Tioga_Pass_MB.brd")
		(comment 1 "Tioga Pass / footprints 1061-1062 of 4770")
	)
	(layers
		(0 "F.Cu" signal "TOP")
		(4 "In1.Cu" signal "L2GND")
		(6 "In2.Cu" signal "L3")
		(8 "In3.Cu" signal "L4GND")
		(10 "In4.Cu" signal "L5")
		(12 "In5.Cu" signal "L6GND")
		(14 "In6.Cu" signal "L7VCC")
		(16 "In7.Cu" signal "L8VCC")
		(18 "In8.Cu" signal "L9GND")
		(20 "In9.Cu" signal "L10")
		(22 "In10.Cu" signal "L11GND")
		(24 "In11.Cu" signal "L12")
		(26 "In12.Cu" signal "L13GND")
		(2 "B.Cu" signal "BOTTOM")
		(9 "F.Adhes" user "F.Adhesive")
		(11 "B.Adhes" user "B.Adhesive")
		(13 "F.Paste" user "Package Geometry/Pastemask Top")
		(15 "B.Paste" user "Package Geometry/Pastemask Bottom")
		(5 "F.SilkS" user "Ref Des/Silkscreen Top")
		(7 "B.SilkS" user "Ref Des/Silkscreen Bottom")
		(1 "F.Mask" user "Board Geometry/Soldermask Top")
		(3 "B.Mask" user "Board Geometry/Soldermask Bottom")
		(17 "Dwgs.User" user "User.Drawings")
		(19 "Cmts.User" user "User.Comments")
		(21 "Eco1.User" user "User.Eco1")
		(23 "Eco2.User" user "User.Eco2")
		(25 "Edge.Cuts" user "Board Geometry/Outline")
		(27 "Margin" user)
		(31 "F.CrtYd" user "Package Geometry/Place Bound Top")
		(29 "B.CrtYd" user "Package Geometry/Place Bound Bottom")
		(35 "F.Fab" user "Ref Des/Assembly Top")
		(33 "B.Fab" user "Ref Des/Assembly Bottom")
	)
	(footprint ""
		(layer "F.Cu")
		(at 485.9274 -136.652 -90)
		(property "Reference" "DS9A6"
			(at -0.19304 3.36169 90)
			(unlocked yes)
			(layer "F.SilkS")
			(effects
				(font
					(size 0.7874 0.5842)
					(thickness 0.1524)
				)
			)
		)
		(property "Value" ""
			(at 0 0 270)
			(layer "F.Fab")
			(effects
				(font
					(size 1.27 1.27)
				)
			)
		)
		(duplicate_pad_numbers_are_jumpers no)
		(fp_line
			(start -1.78562 5.26796)
			(end -1.78562 4.144518)
			(stroke
				(width 0.1524)
				(type default)
			)
			(layer "F.SilkS")
		)
		(fp_line
			(start -2.266442 4.144518)
			(end -1.304798 4.144518)
			(stroke
				(width 0.1524)
				(type default)
			)
			(layer "F.SilkS")
		)
		(fp_line
			(start -1.78562 4.144518)
			(end -2.266442 3.311652)
			(stroke
				(width 0.1524)
				(type default)
			)
			(layer "F.SilkS")
		)
		(fp_line
			(start -2.266442 3.311652)
			(end -1.78562 3.311652)
			(stroke
				(width 0.1524)
				(type default)
			)
			(layer "F.SilkS")
		)
		(fp_line
			(start -1.78562 3.311652)
			(end -1.304798 3.311652)
			(stroke
				(width 0.1524)
				(type default)
			)
			(layer "F.SilkS")
		)
		(fp_line
			(start -1.304798 3.311652)
			(end -1.78562 4.144518)
			(stroke
				(width 0.1524)
				(type default)
			)
			(layer "F.SilkS")
		)
		(fp_line
			(start -1.78562 2.400046)
			(end -1.78562 3.311652)
			(stroke
				(width 0.1524)
				(type default)
			)
			(layer "F.SilkS")
		)
		(fp_poly
			(pts
				(xy 0.6223 2.032) (xy -0.6223 2.032) (xy -0.6223 0.0254) (xy 0.6223 0.0254)
			)
			(stroke
				(width 0)
				(type default)
			)
			(fill no)
			(layer "F.CrtYd")
		)
		(fp_line
			(start -2.266442 4.144518)
			(end -1.304798 4.144518)
			(stroke
				(width 0.1)
				(type default)
			)
			(layer "F.Fab")
		)
		(fp_line
			(start -1.78562 4.144518)
			(end -1.78562 5.26796)
			(stroke
				(width 0.1)
				(type default)
			)
			(layer "F.Fab")
		)
		(fp_line
			(start -1.78562 4.144518)
			(end -2.266442 3.311652)
			(stroke
				(width 0.1)
				(type default)
			)
			(layer "F.Fab")
		)
		(fp_line
			(start -1.782318 3.314446)
			(end -1.782318 2.40284)
			(stroke
				(width 0.1)
				(type default)
			)
			(layer "F.Fab")
		)
		(fp_line
			(start -2.266442 3.311652)
			(end -1.304798 3.311652)
			(stroke
				(width 0.1)
				(type default)
			)
			(layer "F.Fab")
		)
		(fp_line
			(start -1.304798 3.311652)
			(end -1.78562 4.144518)
			(stroke
				(width 0.1)
				(type default)
			)
			(layer "F.Fab")
		)
		(fp_line
			(start -0.6223 2.032)
			(end -0.6223 0.0254)
			(stroke
				(width 0.1)
				(type default)
			)
			(layer "F.Fab")
		)
		(fp_line
			(start 0.6223 2.032)
			(end -0.6223 2.032)
			(stroke
				(width 0.1)
				(type default)
			)
			(layer "F.Fab")
		)
		(fp_line
			(start -0.6223 0.0254)
			(end 0.6223 0.0254)
			(stroke
				(width 0.1)
				(type default)
			)
			(layer "F.Fab")
		)
		(fp_line
			(start 0.6223 0.0254)
			(end 0.6223 2.032)
			(stroke
				(width 0.1)
				(type default)
			)
			(layer "F.Fab")
		)
		(pad "1" smd rect
			(at 0 0 270)
			(size 1.27 1.27)
			(layers "F.Cu" "F.Mask" "F.Paste")
			(net "LED_P5V_STBY")
		)
		(pad "2" smd rect
			(at 0 2.032 270)
			(size 1.27 1.27)
			(layers "F.Cu" "F.Mask" "F.Paste")
			(net "GND")
		)
		(zone
			(layer "F.Cu")
			(hatch none 0.5)
			(connect_pads
				(clearance 0)
			)
			(min_thickness 0.25)
			(keepout
				(tracks not_allowed)
				(vias allowed)
				(pads allowed)
				(copperpour not_allowed)
				(footprints allowed)
			)
			(placement
				(enabled no)
				(sheetname "")
			)
			(fill
				(thermal_gap 0.5)
				(thermal_bridge_width 0.5)
				(island_removal_mode 0)
			)
			(polygon
				(pts
					(xy 484.5304 -137.287) (xy 484.5304 -136.017) (xy 485.2924 -136.017) (xy 485.2924 -137.287)
				)
			)
		)
		(zone
			(layer "F.Cu")
			(hatch none 0.5)
			(connect_pads
				(clearance 0)
			)
			(min_thickness 0.25)
			(keepout
				(tracks allowed)
				(vias not_allowed)
				(pads allowed)
				(copperpour not_allowed)
				(footprints allowed)
			)
			(placement
				(enabled no)
				(sheetname "")
			)
			(fill
				(thermal_gap 0.5)
				(thermal_bridge_width 0.5)
				(island_removal_mode 0)
			)
			(polygon
				(pts
					(xy 484.5304 -137.287) (xy 484.5304 -136.017) (xy 485.2924 -136.017) (xy 485.2924 -137.287)
				)
			)
		)
	)
	(footprint ""
		(layer "F.Cu")
		(at 397.9672 1.7272 90)
		(property "Reference" "R8G22"
			(at 0 0 90)
			(layer "F.SilkS")
			(hide yes)
			(effects
				(font
					(size 1.27 1.27)
				)
			)
		)
		(property "Value" ""
			(at 0 0 90)
			(layer "F.Fab")
			(effects
				(font
					(size 1.27 1.27)
				)
			)
		)
		(duplicate_pad_numbers_are_jumpers no)
		(fp_poly
			(pts
				(xy -0.2794 -0.1016) (xy 0.2794 -0.1016) (xy 0.2794 0.9906) (xy -0.2794 0.9906)
			)
			(stroke
				(width 0)
				(type default)
			)
			(fill no)
			(layer "F.CrtYd")
		)
		(fp_line
			(start 0.2794 -0.1016)
			(end -0.2794 -0.1016)
			(stroke
				(width 0.1)
				(type default)
			)
			(layer "F.Fab")
		)
		(fp_line
			(start -0.2794 -0.1016)
			(end -0.2794 0.9906)
			(stroke
				(width 0.1)
				(type default)
			)
			(layer "F.Fab")
		)
		(fp_line
			(start 0.2794 0.9906)
			(end 0.2794 -0.1016)
			(stroke
				(width 0.1)
				(type default)
			)
			(layer "F.Fab")
		)
		(fp_line
			(start -0.2794 0.9906)
			(end 0.2794 0.9906)
			(stroke
				(width 0.1)
				(type default)
			)
			(layer "F.Fab")
		)
		(pad "1" smd rect
			(at 0 0 90)
			(size 0.508 0.508)
			(layers "F.Cu" "F.Mask" "F.Paste")
			(net "JTAG_TCK")
		)
		(pad "2" smd rect
			(at 0 0.889 90)
			(size 0.508 0.508)
			(layers "F.Cu" "F.Mask" "F.Paste")
			(net "JTAG_TCK_R")
		)
		(zone
			(layer "F.Cu")
			(hatch none 0.5)
			(connect_pads
				(clearance 0)
			)
			(min_thickness 0.25)
			(keepout
				(tracks allowed)
				(vias not_allowed)
				(pads allowed)
				(copperpour not_allowed)
				(footprints allowed)
			)
			(placement
				(enabled no)
				(sheetname "")
			)
			(fill
				(thermal_gap 0.5)
				(thermal_bridge_width 0.5)
				(island_removal_mode 0)
			)
			(polygon
				(pts
					(xy 398.2212 1.9812) (xy 398.2212 1.4732) (xy 398.6022 1.4732) (xy 398.6022 1.9812)
				)
			)
		)
		(zone
			(layer "F.Cu")
			(hatch none 0.5)
			(connect_pads
				(clearance 0)
			)
			(min_thickness 0.25)
			(keepout
				(tracks not_allowed)
				(vias allowed)
				(pads allowed)
				(copperpour not_allowed)
				(footprints allowed)
			)
			(placement
				(enabled no)
				(sheetname "")
			)
			(fill
				(thermal_gap 0.5)
				(thermal_bridge_width 0.5)
				(island_removal_mode 0)
			)
			(polygon
				(pts
					(xy 398.6022 1.9812) (xy 398.6022 1.4732) (xy 398.2212 1.4732) (xy 398.2212 1.9812)
				)
			)
		)
	)
)
